(kicad_pcb
	(version 20260206)
	(generator "pcbnew")
	(generator_version "10.0")
	(general
		(thickness 1.6)
		(legacy_teardrops no)
	)
	(paper "A4")
	(title_block
		(title "9052_F0T_PDB_Converter_Brick_F_V03_1208_1600_OCP.brd")
		(comment 1 "Grand Teton / footprints 124-131 of 578")
	)
	(layers
		(0 "F.Cu" signal "TOP")
		(4 "In1.Cu" signal "GND")
		(6 "In2.Cu" signal "IN1")
		(8 "In3.Cu" signal "GND1")
		(10 "In4.Cu" signal "VCC")
		(12 "In5.Cu" signal "VCC1")
		(14 "In6.Cu" signal "GND2")
		(16 "In7.Cu" signal "IN2")
		(18 "In8.Cu" signal "GND3")
		(2 "B.Cu" signal "BOTTOM")
		(9 "F.Adhes" user "F.Adhesive")
		(11 "B.Adhes" user "B.Adhesive")
		(13 "F.Paste" user "Package Geometry/Pastemask Top")
		(15 "B.Paste" user "Package Geometry/Pastemask Bottom")
		(5 "F.SilkS" user "Ref Des/Silkscreen Top")
		(7 "B.SilkS" user "Ref Des/Silkscreen Bottom")
		(1 "F.Mask" user "Board Geometry/Soldermask Top")
		(3 "B.Mask" user "Board Geometry/Soldermask Bottom")
		(17 "Dwgs.User" user "User.Drawings")
		(19 "Cmts.User" user "User.Comments")
		(21 "Eco1.User" user "User.Eco1")
		(23 "Eco2.User" user "User.Eco2")
		(25 "Edge.Cuts" user "Board Geometry/Outline")
		(27 "Margin" user)
		(31 "F.CrtYd" user "Package Geometry/Place Bound Top")
		(29 "B.CrtYd" user "Package Geometry/Place Bound Bottom")
		(35 "F.Fab" user "Ref Des/Assembly Top")
		(33 "B.Fab" user "Ref Des/Assembly Bottom")
	)
	(footprint ""
		(layer "F.Cu")
		(at 297.538394 -85.2805)
		(property "Reference" "PR6965"
			(at 0 0 0)
			(layer "F.SilkS")
			(hide yes)
			(effects
				(font
					(size 1.27 1.27)
				)
			)
		)
		(property "Value" ""
			(at 0 0 0)
			(layer "F.Fab")
			(effects
				(font
					(size 1.27 1.27)
				)
			)
		)
		(duplicate_pad_numbers_are_jumpers no)
		(fp_line
			(start -1.2954 -0.5842)
			(end 1.2954 -0.5842)
			(stroke
				(width 0.1524)
				(type default)
			)
			(layer "F.SilkS")
		)
		(fp_line
			(start -1.2954 0.5842)
			(end -1.2954 -0.5842)
			(stroke
				(width 0.1524)
				(type default)
			)
			(layer "F.SilkS")
		)
		(fp_line
			(start 1.2954 -0.5842)
			(end 1.2954 0.5842)
			(stroke
				(width 0.1524)
				(type default)
			)
			(layer "F.SilkS")
		)
		(fp_line
			(start 1.2954 0.5842)
			(end -1.2954 0.5842)
			(stroke
				(width 0.1524)
				(type default)
			)
			(layer "F.SilkS")
		)
		(fp_line
			(start -1.1938 -0.406654)
			(end -0.8636 -0.406654)
			(stroke
				(width 0.1)
				(type default)
			)
			(layer "F.Fab")
		)
		(fp_line
			(start -1.1938 0.4064)
			(end -1.1938 -0.406654)
			(stroke
				(width 0.1)
				(type default)
			)
			(layer "F.Fab")
		)
		(fp_line
			(start -0.8636 -0.4572)
			(end 0.8636 -0.4572)
			(stroke
				(width 0.1)
				(type default)
			)
			(layer "F.Fab")
		)
		(fp_line
			(start -0.8636 -0.406654)
			(end -0.8636 -0.4572)
			(stroke
				(width 0.1)
				(type default)
			)
			(layer "F.Fab")
		)
		(fp_line
			(start -0.8636 0.4064)
			(end -1.1938 0.4064)
			(stroke
				(width 0.1)
				(type default)
			)
			(layer "F.Fab")
		)
		(fp_line
			(start -0.8636 0.4318)
			(end -0.8636 0.4064)
			(stroke
				(width 0.1)
				(type default)
			)
			(layer "F.Fab")
		)
		(fp_line
			(start -0.8636 0.4572)
			(end -0.8636 0.4318)
			(stroke
				(width 0.1)
				(type default)
			)
			(layer "F.Fab")
		)
		(fp_line
			(start 0.8636 -0.4572)
			(end 0.8636 -0.406654)
			(stroke
				(width 0.1)
				(type default)
			)
			(layer "F.Fab")
		)
		(fp_line
			(start 0.8636 -0.406654)
			(end 1.1938 -0.406654)
			(stroke
				(width 0.1)
				(type default)
			)
			(layer "F.Fab")
		)
		(fp_line
			(start 0.8636 0.4064)
			(end 0.8636 0.4572)
			(stroke
				(width 0.1)
				(type default)
			)
			(layer "F.Fab")
		)
		(fp_line
			(start 0.8636 0.4572)
			(end -0.8636 0.4572)
			(stroke
				(width 0.1)
				(type default)
			)
			(layer "F.Fab")
		)
		(fp_line
			(start 1.1938 -0.406654)
			(end 1.1938 0.4064)
			(stroke
				(width 0.1)
				(type default)
			)
			(layer "F.Fab")
		)
		(fp_line
			(start 1.1938 0.4064)
			(end 0.8636 0.4064)
			(stroke
				(width 0.1)
				(type default)
			)
			(layer "F.Fab")
		)
		(pad "1" smd rect
			(at -0.7366 0 270)
			(size 0.7112 0.8128)
			(layers "F.Cu" "F.Mask" "F.Paste")
			(net "P52V_HS1_SENSE_N_R2")
		)
		(pad "2" smd rect
			(at 0.7366 0 270)
			(size 0.7112 0.8128)
			(layers "F.Cu" "F.Mask" "F.Paste")
			(net "P52V_HS_4287_ADC_N")
		)
	)
	(footprint ""
		(layer "F.Cu")
		(at 204.089 -66.929 90)
		(property "Reference" "R59"
			(at 0 0 90)
			(layer "F.SilkS")
			(hide yes)
			(effects
				(font
					(size 1.27 1.27)
				)
			)
		)
		(property "Value" ""
			(at 0 0 90)
			(layer "F.Fab")
			(effects
				(font
					(size 1.27 1.27)
				)
			)
		)
		(duplicate_pad_numbers_are_jumpers no)
		(fp_line
			(start 0.7874 -0.4064)
			(end 0.7874 0.4064)
			(stroke
				(width 0.1524)
				(type default)
			)
			(layer "F.SilkS")
		)
		(fp_line
			(start -0.7874 -0.4064)
			(end 0.7874 -0.4064)
			(stroke
				(width 0.1524)
				(type default)
			)
			(layer "F.SilkS")
		)
		(fp_line
			(start 0.7874 0.4064)
			(end -0.7874 0.4064)
			(stroke
				(width 0.1524)
				(type default)
			)
			(layer "F.SilkS")
		)
		(fp_line
			(start -0.7874 0.4064)
			(end -0.7874 -0.4064)
			(stroke
				(width 0.1524)
				(type default)
			)
			(layer "F.SilkS")
		)
		(fp_line
			(start -0.12065 -0.305054)
			(end -0.12065 -0.2794)
			(stroke
				(width 0.1)
				(type default)
			)
			(layer "F.Fab")
		)
		(fp_line
			(start -0.67945 -0.305054)
			(end -0.12065 -0.305054)
			(stroke
				(width 0.1)
				(type default)
			)
			(layer "F.Fab")
		)
		(fp_line
			(start 0.67945 -0.3048)
			(end 0.67945 0.3048)
			(stroke
				(width 0.1)
				(type default)
			)
			(layer "F.Fab")
		)
		(fp_line
			(start 0.12065 -0.3048)
			(end 0.67945 -0.3048)
			(stroke
				(width 0.1)
				(type default)
			)
			(layer "F.Fab")
		)
		(fp_line
			(start 0.12065 -0.2794)
			(end 0.12065 -0.3048)
			(stroke
				(width 0.1)
				(type default)
			)
			(layer "F.Fab")
		)
		(fp_line
			(start -0.12065 -0.2794)
			(end 0.12065 -0.2794)
			(stroke
				(width 0.1)
				(type default)
			)
			(layer "F.Fab")
		)
		(fp_line
			(start 0.120396 0.2794)
			(end -0.12065 0.2794)
			(stroke
				(width 0.1)
				(type default)
			)
			(layer "F.Fab")
		)
		(fp_line
			(start -0.12065 0.2794)
			(end -0.12065 0.3048)
			(stroke
				(width 0.1)
				(type default)
			)
			(layer "F.Fab")
		)
		(fp_line
			(start 0.67945 0.3048)
			(end 0.120396 0.3048)
			(stroke
				(width 0.1)
				(type default)
			)
			(layer "F.Fab")
		)
		(fp_line
			(start 0.120396 0.3048)
			(end 0.120396 0.2794)
			(stroke
				(width 0.1)
				(type default)
			)
			(layer "F.Fab")
		)
		(fp_line
			(start -0.12065 0.3048)
			(end -0.67945 0.3048)
			(stroke
				(width 0.1)
				(type default)
			)
			(layer "F.Fab")
		)
		(fp_line
			(start -0.67945 0.3048)
			(end -0.67945 -0.305054)
			(stroke
				(width 0.1)
				(type default)
			)
			(layer "F.Fab")
		)
		(pad "1" smd circle
			(at -0.40005 0 90)
			(size 0 0)
			(layers "F.Cu" "F.Mask" "F.Paste")
			(net "P3V3_AUX")
		)
		(pad "2" smd circle
			(at 0.40005 0 90)
			(size 0 0)
			(layers "F.Cu" "F.Mask" "F.Paste")
			(net "LED_D3_R")
		)
	)
	(footprint ""
		(layer "F.Cu")
		(at 184.52846 -49.911)
		(property "Reference" "PC133"
			(at 0 0 0)
			(layer "F.SilkS")
			(hide yes)
			(effects
				(font
					(size 1.27 1.27)
				)
			)
		)
		(property "Value" ""
			(at 0 0 0)
			(layer "F.Fab")
			(effects
				(font
					(size 1.27 1.27)
				)
			)
		)
		(duplicate_pad_numbers_are_jumpers no)
		(fp_line
			(start -1.524 -0.762)
			(end 1.524 -0.762)
			(stroke
				(width 0.1524)
				(type default)
			)
			(layer "F.SilkS")
		)
		(fp_line
			(start -1.524 0.762)
			(end -1.524 -0.762)
			(stroke
				(width 0.1524)
				(type default)
			)
			(layer "F.SilkS")
		)
		(fp_line
			(start 1.524 -0.762)
			(end 1.524 0.762)
			(stroke
				(width 0.1524)
				(type default)
			)
			(layer "F.SilkS")
		)
		(fp_line
			(start 1.524 0.762)
			(end -1.524 0.762)
			(stroke
				(width 0.1524)
				(type default)
			)
			(layer "F.SilkS")
		)
		(fp_line
			(start -1.1049 -0.724916)
			(end -1.1049 0.724916)
			(stroke
				(width 0.1)
				(type default)
			)
			(layer "F.Fab")
		)
		(fp_line
			(start -1.1049 0.724916)
			(end 1.1049 0.724916)
			(stroke
				(width 0.1)
				(type default)
			)
			(layer "F.Fab")
		)
		(fp_line
			(start 1.1049 -0.724916)
			(end -1.1049 -0.724916)
			(stroke
				(width 0.1)
				(type default)
			)
			(layer "F.Fab")
		)
		(fp_line
			(start 1.1049 0.724916)
			(end 1.1049 -0.724916)
			(stroke
				(width 0.1)
				(type default)
			)
			(layer "F.Fab")
		)
		(pad "1" smd rect
			(at -0.889 0 180)
			(size 1.016 1.27)
			(layers "F.Cu" "F.Mask" "F.Paste")
			(net "P12V_BRICK")
		)
		(pad "2" smd rect
			(at 0.889 0 180)
			(size 1.016 1.27)
			(layers "F.Cu" "F.Mask" "F.Paste")
			(net "GND")
		)
	)
	(footprint ""
		(layer "F.Cu")
		(at 227.33 -95.504 -90)
		(property "Reference" "C33"
			(at 0 0 270)
			(layer "F.SilkS")
			(hide yes)
			(effects
				(font
					(size 1.27 1.27)
				)
			)
		)
		(property "Value" ""
			(at 0 0 270)
			(layer "F.Fab")
			(effects
				(font
					(size 1.27 1.27)
				)
			)
		)
		(duplicate_pad_numbers_are_jumpers no)
		(fp_line
			(start -2.2098 0.9398)
			(end -2.2098 -0.9398)
			(stroke
				(width 0.1524)
				(type default)
			)
			(layer "F.SilkS")
		)
		(fp_line
			(start 2.2098 0.9398)
			(end -2.2098 0.9398)
			(stroke
				(width 0.1524)
				(type default)
			)
			(layer "F.SilkS")
		)
		(fp_line
			(start -2.2098 -0.9398)
			(end 2.2098 -0.9398)
			(stroke
				(width 0.1524)
				(type default)
			)
			(layer "F.SilkS")
		)
		(fp_line
			(start 2.2098 -0.9398)
			(end 2.2098 0.9398)
			(stroke
				(width 0.1524)
				(type default)
			)
			(layer "F.SilkS")
		)
		(fp_line
			(start -1.700022 0.899922)
			(end -1.700022 -0.899922)
			(stroke
				(width 0.1)
				(type default)
			)
			(layer "F.Fab")
		)
		(fp_line
			(start 1.700022 0.899922)
			(end -1.700022 0.899922)
			(stroke
				(width 0.1)
				(type default)
			)
			(layer "F.Fab")
		)
		(fp_line
			(start -1.700022 -0.899922)
			(end 1.700022 -0.899922)
			(stroke
				(width 0.1)
				(type default)
			)
			(layer "F.Fab")
		)
		(fp_line
			(start 1.700022 -0.899922)
			(end 1.700022 0.899922)
			(stroke
				(width 0.1)
				(type default)
			)
			(layer "F.Fab")
		)
		(pad "1" smd rect
			(at -1.4732 0 90)
			(size 1.1684 1.5748)
			(layers "F.Cu" "F.Mask" "F.Paste")
			(net "P52V_HS")
		)
		(pad "2" smd rect
			(at 1.4732 0 90)
			(size 1.1684 1.5748)
			(layers "F.Cu" "F.Mask" "F.Paste")
			(net "GND")
		)
	)
	(footprint ""
		(layer "F.Cu")
		(at 79.375 -60.96)
		(property "Reference" "PC97"
			(at -1.524 -3.52933 0)
			(unlocked yes)
			(layer "F.SilkS")
			(effects
				(font
					(size 0.7874 0.5842)
					(thickness 0.1524)
				)
				(justify left)
			)
		)
		(property "Value" ""
			(at 0 0 0)
			(layer "F.Fab")
			(effects
				(font
					(size 1.27 1.27)
				)
			)
		)
		(duplicate_pad_numbers_are_jumpers no)
		(fp_line
			(start 5.2578 2.499868)
			(end -5.2578 2.499868)
			(stroke
				(width 0.1524)
				(type default)
			)
			(layer "F.SilkS")
		)
		(fp_circle
			(center 0 2.499868)
			(end 5.2578 2.499868)
			(stroke
				(width 0.1524)
				(type default)
			)
			(fill no)
			(layer "F.SilkS")
		)
		(fp_poly
			(pts
				(arc
					(start 5.2578 2.499868)
					(mid 0 7.757922)
					(end -5.2578 2.499868)
				)
			)
			(stroke
				(width 0)
				(type default)
			)
			(fill yes)
			(layer "F.SilkS")
		)
		(fp_circle
			(center 0 2.499868)
			(end 5.2578 2.499868)
			(stroke
				(width 0.1)
				(type default)
			)
			(fill no)
			(layer "F.Fab")
		)
		(pad "1" thru_hole rect
			(at 0 0 270)
			(size 1.524 1.524)
			(drill 1.016)
			(layers "*.Cu" "*.Mask")
			(remove_unused_layers no)
			(net "P12V_BRICK")
			(clearance 0)
			(padstack
				(mode front_inner_back)
				(layer "Inner"
					(shape circle)
					(size 1.524 1.524)
					(clearance 0)
				)
				(layer "B.Cu"
					(shape rect)
					(size 1.524 1.524)
					(clearance 0)
				)
			)
		)
		(pad "2" thru_hole circle
			(at 0 4.99999 270)
			(size 1.524 1.524)
			(drill 1.016)
			(layers "*.Cu" "*.Mask")
			(remove_unused_layers no)
			(net "GND")
			(clearance 0)
		)
	)
	(footprint ""
		(layer "F.Cu")
		(at 198.717916 -66.956686 90)
		(property "Reference" "R56"
			(at 0 0 90)
			(layer "F.SilkS")
			(hide yes)
			(effects
				(font
					(size 1.27 1.27)
				)
			)
		)
		(property "Value" ""
			(at 0 0 90)
			(layer "F.Fab")
			(effects
				(font
					(size 1.27 1.27)
				)
			)
		)
		(duplicate_pad_numbers_are_jumpers no)
		(fp_line
			(start 0.7874 -0.4064)
			(end 0.7874 0.4064)
			(stroke
				(width 0.1524)
				(type default)
			)
			(layer "F.SilkS")
		)
		(fp_line
			(start -0.7874 -0.4064)
			(end 0.7874 -0.4064)
			(stroke
				(width 0.1524)
				(type default)
			)
			(layer "F.SilkS")
		)
		(fp_line
			(start 0.7874 0.4064)
			(end -0.7874 0.4064)
			(stroke
				(width 0.1524)
				(type default)
			)
			(layer "F.SilkS")
		)
		(fp_line
			(start -0.7874 0.4064)
			(end -0.7874 -0.4064)
			(stroke
				(width 0.1524)
				(type default)
			)
			(layer "F.SilkS")
		)
		(fp_line
			(start -0.12065 -0.305054)
			(end -0.12065 -0.2794)
			(stroke
				(width 0.1)
				(type default)
			)
			(layer "F.Fab")
		)
		(fp_line
			(start -0.67945 -0.305054)
			(end -0.12065 -0.305054)
			(stroke
				(width 0.1)
				(type default)
			)
			(layer "F.Fab")
		)
		(fp_line
			(start 0.67945 -0.3048)
			(end 0.67945 0.3048)
			(stroke
				(width 0.1)
				(type default)
			)
			(layer "F.Fab")
		)
		(fp_line
			(start 0.12065 -0.3048)
			(end 0.67945 -0.3048)
			(stroke
				(width 0.1)
				(type default)
			)
			(layer "F.Fab")
		)
		(fp_line
			(start 0.12065 -0.2794)
			(end 0.12065 -0.3048)
			(stroke
				(width 0.1)
				(type default)
			)
			(layer "F.Fab")
		)
		(fp_line
			(start -0.12065 -0.2794)
			(end 0.12065 -0.2794)
			(stroke
				(width 0.1)
				(type default)
			)
			(layer "F.Fab")
		)
		(fp_line
			(start 0.120396 0.2794)
			(end -0.12065 0.2794)
			(stroke
				(width 0.1)
				(type default)
			)
			(layer "F.Fab")
		)
		(fp_line
			(start -0.12065 0.2794)
			(end -0.12065 0.3048)
			(stroke
				(width 0.1)
				(type default)
			)
			(layer "F.Fab")
		)
		(fp_line
			(start 0.67945 0.3048)
			(end 0.120396 0.3048)
			(stroke
				(width 0.1)
				(type default)
			)
			(layer "F.Fab")
		)
		(fp_line
			(start 0.120396 0.3048)
			(end 0.120396 0.2794)
			(stroke
				(width 0.1)
				(type default)
			)
			(layer "F.Fab")
		)
		(fp_line
			(start -0.12065 0.3048)
			(end -0.67945 0.3048)
			(stroke
				(width 0.1)
				(type default)
			)
			(layer "F.Fab")
		)
		(fp_line
			(start -0.67945 0.3048)
			(end -0.67945 -0.305054)
			(stroke
				(width 0.1)
				(type default)
			)
			(layer "F.Fab")
		)
		(pad "1" smd circle
			(at -0.40005 0 90)
			(size 0 0)
			(layers "F.Cu" "F.Mask" "F.Paste")
			(net "P12V_BRICK")
		)
		(pad "2" smd circle
			(at 0.40005 0 90)
			(size 0 0)
			(layers "F.Cu" "F.Mask" "F.Paste")
			(net "LED_D2_R1")
		)
	)
	(footprint ""
		(layer "F.Cu")
		(at 278.892 -47.752 180)
		(property "Reference" "PR21"
			(at 0 0 180)
			(layer "F.SilkS")
			(hide yes)
			(effects
				(font
					(size 1.27 1.27)
				)
			)
		)
		(property "Value" ""
			(at 0 0 180)
			(layer "F.Fab")
			(effects
				(font
					(size 1.27 1.27)
				)
			)
		)
		(duplicate_pad_numbers_are_jumpers no)
		(fp_line
			(start 0.7874 0.4064)
			(end -0.7874 0.4064)
			(stroke
				(width 0.1524)
				(type default)
			)
			(layer "F.SilkS")
		)
		(fp_line
			(start 0.7874 -0.4064)
			(end 0.7874 0.4064)
			(stroke
				(width 0.1524)
				(type default)
			)
			(layer "F.SilkS")
		)
		(fp_line
			(start -0.7874 0.4064)
			(end -0.7874 -0.4064)
			(stroke
				(width 0.1524)
				(type default)
			)
			(layer "F.SilkS")
		)
		(fp_line
			(start -0.7874 -0.4064)
			(end 0.7874 -0.4064)
			(stroke
				(width 0.1524)
				(type default)
			)
			(layer "F.SilkS")
		)
		(fp_line
			(start 0.67945 0.3048)
			(end 0.120396 0.3048)
			(stroke
				(width 0.1)
				(type default)
			)
			(layer "F.Fab")
		)
		(fp_line
			(start 0.67945 -0.3048)
			(end 0.67945 0.3048)
			(stroke
				(width 0.1)
				(type default)
			)
			(layer "F.Fab")
		)
		(fp_line
			(start 0.12065 -0.2794)
			(end 0.12065 -0.3048)
			(stroke
				(width 0.1)
				(type default)
			)
			(layer "F.Fab")
		)
		(fp_line
			(start 0.12065 -0.3048)
			(end 0.67945 -0.3048)
			(stroke
				(width 0.1)
				(type default)
			)
			(layer "F.Fab")
		)
		(fp_line
			(start 0.120396 0.3048)
			(end 0.120396 0.2794)
			(stroke
				(width 0.1)
				(type default)
			)
			(layer "F.Fab")
		)
		(fp_line
			(start 0.120396 0.2794)
			(end -0.12065 0.2794)
			(stroke
				(width 0.1)
				(type default)
			)
			(layer "F.Fab")
		)
		(fp_line
			(start -0.12065 0.3048)
			(end -0.67945 0.3048)
			(stroke
				(width 0.1)
				(type default)
			)
			(layer "F.Fab")
		)
		(fp_line
			(start -0.12065 0.2794)
			(end -0.12065 0.3048)
			(stroke
				(width 0.1)
				(type default)
			)
			(layer "F.Fab")
		)
		(fp_line
			(start -0.12065 -0.2794)
			(end 0.12065 -0.2794)
			(stroke
				(width 0.1)
				(type default)
			)
			(layer "F.Fab")
		)
		(fp_line
			(start -0.12065 -0.305054)
			(end -0.12065 -0.2794)
			(stroke
				(width 0.1)
				(type default)
			)
			(layer "F.Fab")
		)
		(fp_line
			(start -0.67945 0.3048)
			(end -0.67945 -0.305054)
			(stroke
				(width 0.1)
				(type default)
			)
			(layer "F.Fab")
		)
		(fp_line
			(start -0.67945 -0.305054)
			(end -0.12065 -0.305054)
			(stroke
				(width 0.1)
				(type default)
			)
			(layer "F.Fab")
		)
		(pad "1" smd circle
			(at -0.40005 0 180)
			(size 0 0)
			(layers "F.Cu" "F.Mask" "F.Paste")
			(net "P52V_HS1_ISET")
		)
		(pad "2" smd circle
			(at 0.40005 0 180)
			(size 0 0)
			(layers "F.Cu" "F.Mask" "F.Paste")
			(net "GND_FIELD_SIGNAL")
		)
	)
	(footprint ""
		(layer "F.Cu")
		(at 166.0398 -12.4968 90)
		(property "Reference" "PC568"
			(at 0 0 90)
			(layer "F.SilkS")
			(hide yes)
			(effects
				(font
					(size 1.27 1.27)
				)
			)
		)
		(property "Value" ""
			(at 0 0 90)
			(layer "F.Fab")
			(effects
				(font
					(size 1.27 1.27)
				)
			)
		)
		(duplicate_pad_numbers_are_jumpers no)
		(fp_line
			(start 1.524 -0.762)
			(end 1.524 0.762)
			(stroke
				(width 0.1524)
				(type default)
			)
			(layer "F.SilkS")
		)
		(fp_line
			(start -1.524 -0.762)
			(end 1.524 -0.762)
			(stroke
				(width 0.1524)
				(type default)
			)
			(layer "F.SilkS")
		)
		(fp_line
			(start 1.524 0.762)
			(end -1.524 0.762)
			(stroke
				(width 0.1524)
				(type default)
			)
			(layer "F.SilkS")
		)
		(fp_line
			(start -1.524 0.762)
			(end -1.524 -0.762)
			(stroke
				(width 0.1524)
				(type default)
			)
			(layer "F.SilkS")
		)
		(fp_line
			(start 1.1049 -0.724916)
			(end -1.1049 -0.724916)
			(stroke
				(width 0.1)
				(type default)
			)
			(layer "F.Fab")
		)
		(fp_line
			(start -1.1049 -0.724916)
			(end -1.1049 0.724916)
			(stroke
				(width 0.1)
				(type default)
			)
			(layer "F.Fab")
		)
		(fp_line
			(start 1.1049 0.724916)
			(end 1.1049 -0.724916)
			(stroke
				(width 0.1)
				(type default)
			)
			(layer "F.Fab")
		)
		(fp_line
			(start -1.1049 0.724916)
			(end 1.1049 0.724916)
			(stroke
				(width 0.1)
				(type default)
			)
			(layer "F.Fab")
		)
		(pad "1" smd rect
			(at -0.889 0 270)
			(size 1.016 1.27)
			(layers "F.Cu" "F.Mask" "F.Paste")
			(net "SW_P12V_FILT__P3V3_AUX")
		)
		(pad "2" smd rect
			(at 0.889 0 270)
			(size 1.016 1.27)
			(layers "F.Cu" "F.Mask" "F.Paste")
			(net "GND")
		)
	)
)
